# BASEBOARD_FAB2 (Tioga Pass) — schematic netlist excerpt (pin names and nets, part order shuffled) for the footprints in the layout excerpt that follows; sources: Cadence DE-HDL packaged netlist, KiCad conversion of Wiwynn_Tioga_Pass_MB.brd

C2M4  CAP_A  0.1UF 16V 10% X7R  pkg 0402V  page 116 : A = P2E_SSB_BMC_TX_DP ; B = P2E_SSB_BMC_TX_C_DP
C3M35  CAP  0.22UF 16V 10% X7R  pkg 0402  page 105 : A = P3E_CPU0_PE1_PCH_R_RXN<9> ; B = P3E_CPU0_PE1_PCH_RXN<9>
C1C18  SC1U10V2KX-4-GP  10%  pkg SMD-BCG6  page 209 : \1\ = P5V_STBY ; \2\ = GND

(kicad_pcb
	(version 20260206)
	(generator "pcbnew")
	(generator_version "10.0")
	(general
		(thickness 1.6)
		(legacy_teardrops no)
	)
	(paper "A4")
	(title_block
		(title "Wiwynn_Tioga_Pass_MB.brd")
		(comment 1 "Tioga Pass / footprints 2617-2619 of 4770")
	)
	(layers
		(0 "F.Cu" signal "TOP")
		(4 "In1.Cu" signal "L2GND")
		(6 "In2.Cu" signal "L3")
		(8 "In3.Cu" signal "L4GND")
		(10 "In4.Cu" signal "L5")
		(12 "In5.Cu" signal "L6GND")
		(14 "In6.Cu" signal "L7VCC")
		(16 "In7.Cu" signal "L8VCC")
		(18 "In8.Cu" signal "L9GND")
		(20 "In9.Cu" signal "L10")
		(22 "In10.Cu" signal "L11GND")
		(24 "In11.Cu" signal "L12")
		(26 "In12.Cu" signal "L13GND")
		(2 "B.Cu" signal "BOTTOM")
		(9 "F.Adhes" user "F.Adhesive")
		(11 "B.Adhes" user "B.Adhesive")
		(13 "F.Paste" user "Package Geometry/Pastemask Top")
		(15 "B.Paste" user "Package Geometry/Pastemask Bottom")
		(5 "F.SilkS" user "Ref Des/Silkscreen Top")
		(7 "B.SilkS" user "Ref Des/Silkscreen Bottom")
		(1 "F.Mask" user "Board Geometry/Soldermask Top")
		(3 "B.Mask" user "Board Geometry/Soldermask Bottom")
		(17 "Dwgs.User" user "User.Drawings")
		(19 "Cmts.User" user "User.Comments")
		(21 "Eco1.User" user "User.Eco1")
		(23 "Eco2.User" user "User.Eco2")
		(25 "Edge.Cuts" user "Board Geometry/Outline")
		(27 "Margin" user)
		(31 "F.CrtYd" user "Package Geometry/Place Bound Top")
		(29 "B.CrtYd" user "Package Geometry/Place Bound Bottom")
		(35 "F.Fab" user "Ref Des/Assembly Top")
		(33 "B.Fab" user "Ref Des/Assembly Bottom")
	)
	(footprint ""
		(layer "B.Cu")
		(at 368.716814 -125.507242 -90)
		(property "Reference" "C3M35"
			(at 0 0 90)
			(layer "B.SilkS")
			(hide yes)
			(effects
				(font
					(size 1.27 1.27)
				)
				(justify mirror)
			)
		)
		(property "Value" ""
			(at 0 0 90)
			(layer "B.Fab")
			(effects
				(font
					(size 1.27 1.27)
				)
				(justify mirror)
			)
		)
		(duplicate_pad_numbers_are_jumpers no)
		(fp_poly
			(pts
				(xy -0.3048 -0.1016) (xy -0.3048 0.9906) (xy 0.3048 0.9906) (xy 0.3048 -0.1016)
			)
			(stroke
				(width 0)
				(type default)
			)
			(fill no)
			(layer "B.CrtYd")
		)
		(fp_line
			(start -0.3048 0.9906)
			(end -0.3048 -0.1016)
			(stroke
				(width 0.1)
				(type default)
			)
			(layer "B.Fab")
		)
		(fp_line
			(start 0.3048 0.9906)
			(end -0.3048 0.9906)
			(stroke
				(width 0.1)
				(type default)
			)
			(layer "B.Fab")
		)
		(fp_line
			(start -0.3048 -0.1016)
			(end 0.3048 -0.1016)
			(stroke
				(width 0.1)
				(type default)
			)
			(layer "B.Fab")
		)
		(fp_line
			(start 0.3048 -0.1016)
			(end 0.3048 0.9906)
			(stroke
				(width 0.1)
				(type default)
			)
			(layer "B.Fab")
		)
		(pad "1" smd rect
			(at 0 0 90)
			(size 0.508 0.508)
			(layers "B.Cu" "B.Mask" "B.Paste")
			(net "P3E_CPU0_PE1_PCH_R_RXN<9>")
		)
		(pad "2" smd rect
			(at 0 0.889 90)
			(size 0.508 0.508)
			(layers "B.Cu" "B.Mask" "B.Paste")
			(net "P3E_CPU0_PE1_PCH_RXN<9>")
		)
		(zone
			(layer "B.Cu")
			(hatch none 0.5)
			(connect_pads
				(clearance 0)
			)
			(min_thickness 0.25)
			(keepout
				(tracks not_allowed)
				(vias allowed)
				(pads allowed)
				(copperpour not_allowed)
				(footprints allowed)
			)
			(placement
				(enabled no)
				(sheetname "")
			)
			(fill
				(thermal_gap 0.5)
				(thermal_bridge_width 0.5)
				(island_removal_mode 0)
			)
			(polygon
				(pts
					(xy 368.081814 -125.253242) (xy 368.081814 -125.761242) (xy 368.462814 -125.761242) (xy 368.462814 -125.253242)
				)
			)
		)
		(zone
			(layer "B.Cu")
			(hatch none 0.5)
			(connect_pads
				(clearance 0)
			)
			(min_thickness 0.25)
			(keepout
				(tracks allowed)
				(vias not_allowed)
				(pads allowed)
				(copperpour not_allowed)
				(footprints allowed)
			)
			(placement
				(enabled no)
				(sheetname "")
			)
			(fill
				(thermal_gap 0.5)
				(thermal_bridge_width 0.5)
				(island_removal_mode 0)
			)
			(polygon
				(pts
					(xy 368.462814 -125.253242) (xy 368.462814 -125.761242) (xy 368.081814 -125.761242) (xy 368.081814 -125.253242)
				)
			)
		)
	)
	(footprint ""
		(layer "B.Cu")
		(at 33.622996 -85.733382 90)
		(property "Reference" "C1C18"
			(at 0 0 90)
			(layer "B.SilkS")
			(hide yes)
			(effects
				(font
					(size 1.27 1.27)
				)
				(justify mirror)
			)
		)
		(property "Value" "*"
			(at -1.1811 -2.8194 90)
			(unlocked yes)
			(layer "B.Fab")
			(hide yes)
			(effects
				(font
					(size 1.27 1.016)
					(thickness 0.1524)
				)
				(justify mirror)
			)
		)
		(property "Device Type" "SC1U10V2KX-4-GP_SMD-BCG6-SC1U1A"
			(at -1.1811 -4.3434 90)
			(unlocked yes)
			(layer "B.Fab")
			(hide yes)
			(effects
				(font
					(size 1.27 1.016)
					(thickness 0.1524)
				)
				(justify mirror)
			)
		)
		(duplicate_pad_numbers_are_jumpers no)
		(fp_rect
			(start 0.4318 0.9525)
			(end -0.4318 -0.9525)
			(stroke
				(width 0)
				(type default)
			)
			(fill no)
			(layer "B.CrtYd")
		)
		(fp_rect
			(start 0.4318 0.9525)
			(end -0.4318 -0.9525)
			(stroke
				(width 0)
				(type default)
			)
			(fill no)
			(layer "B.Fab")
		)
		(pad "1" smd custom
			(at 0 -0.4445 270)
			(size 0.1524 0.1524)
			(layers "B.Cu" "B.Mask" "B.Paste")
			(net "P5V_STBY")
			(options
				(clearance outline)
				(anchor circle)
			)
			(primitives
				(gr_poly
					(pts
						(arc
							(start 0.3048 0.2032)
							(mid 0.275042 0.275042)
							(end 0.2032 0.3048)
						)
						(arc
							(start -0.2032 0.3048)
							(mid -0.275042 0.275042)
							(end -0.3048 0.2032)
						)
						(arc
							(start -0.3048 -0.2032)
							(mid -0.275042 -0.275042)
							(end -0.2032 -0.3048)
						)
						(arc
							(start 0.2032 -0.3048)
							(mid 0.275042 -0.275042)
							(end 0.3048 -0.2032)
						)
					)
					(width 0)
					(fill yes)
				)
			)
		)
		(pad "2" smd custom
			(at 0 0.4445 270)
			(size 0.1524 0.1524)
			(layers "B.Cu" "B.Mask" "B.Paste")
			(net "GND")
			(options
				(clearance outline)
				(anchor circle)
			)
			(primitives
				(gr_poly
					(pts
						(arc
							(start 0.3048 0.2032)
							(mid 0.275042 0.275042)
							(end 0.2032 0.3048)
						)
						(arc
							(start -0.2032 0.3048)
							(mid -0.275042 0.275042)
							(end -0.3048 0.2032)
						)
						(arc
							(start -0.3048 -0.2032)
							(mid -0.275042 -0.275042)
							(end -0.2032 -0.3048)
						)
						(arc
							(start 0.2032 -0.3048)
							(mid 0.275042 -0.275042)
							(end 0.3048 -0.2032)
						)
					)
					(width 0)
					(fill yes)
				)
			)
		)
	)
	(footprint ""
		(layer "B.Cu")
		(at 399.530824 -124.738384 90)
		(property "Reference" "C2M4"
			(at 0 0 90)
			(layer "B.SilkS")
			(hide yes)
			(effects
				(font
					(size 1.27 1.27)
				)
				(justify mirror)
			)
		)
		(property "Value" ""
			(at 0 0 90)
			(layer "B.Fab")
			(effects
				(font
					(size 1.27 1.27)
				)
				(justify mirror)
			)
		)
		(duplicate_pad_numbers_are_jumpers no)
		(fp_poly
			(pts
				(xy -0.3048 -0.1016) (xy -0.3048 0.9906) (xy 0.3048 0.9906) (xy 0.3048 -0.1016)
			)
			(stroke
				(width 0)
				(type default)
			)
			(fill no)
			(layer "B.CrtYd")
		)
		(fp_line
			(start 0.3048 -0.1016)
			(end 0.3048 0.9906)
			(stroke
				(width 0.1)
				(type default)
			)
			(layer "B.Fab")
		)
		(fp_line
			(start -0.3048 -0.1016)
			(end 0.3048 -0.1016)
			(stroke
				(width 0.1)
				(type default)
			)
			(layer "B.Fab")
		)
		(fp_line
			(start 0.3048 0.9906)
			(end -0.3048 0.9906)
			(stroke
				(width 0.1)
				(type default)
			)
			(layer "B.Fab")
		)
		(fp_line
			(start -0.3048 0.9906)
			(end -0.3048 -0.1016)
			(stroke
				(width 0.1)
				(type default)
			)
			(layer "B.Fab")
		)
		(pad "1" smd rect
			(at 0 0 270)
			(size 0.508 0.508)
			(layers "B.Cu" "B.Mask" "B.Paste")
			(net "P2E_SSB_BMC_TX_DP")
		)
		(pad "2" smd rect
			(at 0 0.889 270)
			(size 0.508 0.508)
			(layers "B.Cu" "B.Mask" "B.Paste")
			(net "P2E_SSB_BMC_TX_C_DP")
		)
		(zone
			(layer "B.Cu")
			(hatch none 0.5)
			(connect_pads
				(clearance 0)
			)
			(min_thickness 0.25)
			(keepout
				(tracks allowed)
				(vias not_allowed)
				(pads allowed)
				(copperpour not_allowed)
				(footprints allowed)
			)
			(placement
				(enabled no)
				(sheetname "")
			)
			(fill
				(thermal_gap 0.5)
				(thermal_bridge_width 0.5)
				(island_removal_mode 0)
			)
			(polygon
				(pts
					(xy 399.784824 -124.992384) (xy 399.784824 -124.484384) (xy 400.165824 -124.484384) (xy 400.165824 -124.992384)
				)
			)
		)
		(zone
			(layer "B.Cu")
			(hatch none 0.5)
			(connect_pads
				(clearance 0)
			)
			(min_thickness 0.25)
			(keepout
				(tracks not_allowed)
				(vias allowed)
				(pads allowed)
				(copperpour not_allowed)
				(footprints allowed)
			)
			(placement
				(enabled no)
				(sheetname "")
			)
			(fill
				(thermal_gap 0.5)
				(thermal_bridge_width 0.5)
				(island_removal_mode 0)
			)
			(polygon
				(pts
					(xy 400.165824 -124.992384) (xy 400.165824 -124.484384) (xy 399.784824 -124.484384) (xy 399.784824 -124.992384)
				)
			)
		)
	)
)
